# BASEBOARD_FAB2 (Tioga Pass) — schematic netlist excerpt (pin names and nets, part order shuffled) for the footprints in the layout excerpt that follows; sources: Cadence DE-HDL packaged netlist, KiCad conversion of Wiwynn_Tioga_Pass_MB.brd

J4A2  SCONN288_H44441004  SCONN  pkg PIP  page 51
  \12v\(1)  = P12V_NVDIMM_DEF
  VSS(93)  = GND
  DQ(4)  = M_E_DQ<5>
  VSS(92)  = GND
  DQ(0)  = M_E_DQ<1>
  VSS(91)  = GND
  DQS9P  = M_E_DQS_DP<9>
  DQS9N  = M_E_DQS_DN<9>
  VSS(90)  = GND
  DQ(6)  = M_E_DQ<7>
  VSS(89)  = GND
  DQ(2)  = M_E_DQ<3>
  VSS(88)  = GND
  DQ(12)  = M_E_DQ<13>
  VSS(87)  = GND
  DQ(8)  = M_E_DQ<9>
  VSS(86)  = GND
  DQS10P  = M_E_DQS_DP<10>
  DQS10N  = M_E_DQS_DN<10>
  VSS(85)  = GND
  DQ(14)  = M_E_DQ<15>
  VSS(84)  = GND
  DQ(10)  = M_E_DQ<11>
  VSS(83)  = GND
  DQ(20)  = M_E_DQ<21>
  VSS(82)  = GND
  DQ(16)  = M_E_DQ<17>
  VSS(81)  = GND
  DQS11P  = M_E_DQS_DP<11>
  DQS11N  = M_E_DQS_DN<11>
  VSS(80)  = GND
  DQ(22)  = M_E_DQ<23>
  VSS(79)  = GND
  DQ(18)  = M_E_DQ<19>
  VSS(78)  = GND
  DQ(28)  = M_E_DQ<29>
  VSS(77)  = GND
  DQ(24)  = M_E_DQ<25>
  VSS(76)  = GND
  DQS12P  = M_E_DQS_DP<12>
  DQS12N  = M_E_DQS_DN<12>
  VSS(75)  = GND
  DQ(30)  = M_E_DQ<31>
  VSS(74)  = GND
  DQ(26)  = M_E_DQ<27>
  VSS(73)  = GND
  CB(4)  = M_E_ECC<5>
  VSS(72)  = GND
  CB(0)  = M_E_ECC<1>
  VSS(71)  = GND
  DQS17P  = M_E_DQS_DP<17>
  DQS17N  = M_E_DQS_DN<17>
  VSS(70)  = GND
  CB(6)  = M_E_ECC<7>
  VSS(69)  = GND
  CB(2)  = M_E_ECC<3>
  VSS(68)  = GND
  RESET_N  = M_DEF_RST_N
  VDD(25)  = PVDDQ_DEF
  CKE(0)  = M_E_CKE<0>
  VDD(24)  = PVDDQ_DEF
  ACT_N  = M_E_ACT_N
  BG(0)  = M_E_BG<0>
  VDD(23)  = PVDDQ_DEF
  A12  = M_E_MA<12>
  A9  = M_E_MA<9>
  VDD(22)  = PVDDQ_DEF
  A8  = M_E_MA<8>
  A6  = M_E_MA<6>
  VDD(21)  = PVDDQ_DEF
  A3  = M_E_MA<3>
  A1  = M_E_MA<1>
  VDD(20)  = PVDDQ_DEF
  CK0P  = M_E_CLK_DP<0>
  CK0N  = M_E_CLK_DN<0>
  VDD(19)  = PVDDQ_DEF
  VTT(1)  = PVTT_DEF
  EVENT_N  = FM_DIMM_EVENT_COD_N
  A0  = M_E_MA<0>
  VDD(18)  = PVDDQ_DEF
  BA(0)  = M_E_BA<0>
  A16_RAS_N  = M_E_MA<16>
  VDD(17)  = PVDDQ_DEF
  S0_N  = M_E_CS_N<0>
  VDD(16)  = PVDDQ_DEF
  A15_CAS_N  = M_E_MA<15>
  ODT(0)  = M_E_ODT<0>
  VDD(15)  = PVDDQ_DEF
  S1_N  = M_E_CS_N<1>
  VDD(14)  = PVDDQ_DEF
  ODT(1)  = M_E_ODT<1>
  VDD(13)  = PVDDQ_DEF
  S2_N_C(0)  = M_E_CS_N<2>
  VSS(67)  = GND
  DQ(36)  = M_E_DQ<37>
  VSS(66)  = GND
  DQ(32)  = M_E_DQ<33>
  VSS(65)  = GND
  DQS13P  = M_E_DQS_DP<13>
  DQS13N  = M_E_DQS_DN<13>
  VSS(64)  = GND
  DQ(38)  = M_E_DQ<39>
  VSS(63)  = GND
  DQ(34)  = M_E_DQ<35>
  VSS(62)  = GND
  DQ(44)  = M_E_DQ<45>
  VSS(61)  = GND
  DQ(40)  = M_E_DQ<41>
  VSS(60)  = GND
  DQS14P  = M_E_DQS_DP<14>
  DQS14N  = M_E_DQS_DN<14>
  VSS(59)  = GND
  DQ(46)  = M_E_DQ<47>
  VSS(58)  = GND
  DQ(42)  = M_E_DQ<43>
  VSS(57)  = GND
  DQ(52)  = M_E_DQ<53>
  VSS(56)  = GND
  DQ(48)  = M_E_DQ<49>
  VSS(55)  = GND
  DQS15P  = M_E_DQS_DP<15>
  DQS15N  = M_E_DQS_DN<15>
  VSS(54)  = GND
  DQ(54)  = M_E_DQ<55>
  VSS(53)  = GND
  DQ(50)  = M_E_DQ<51>
  VSS(52)  = GND
  DQ(60)  = M_E_DQ<61>
  VSS(51)  = GND
  DQ(56)  = M_E_DQ<57>
  VSS(50)  = GND
  DQS16P  = M_E_DQS_DP<16>
  DQS16N  = M_E_DQS_DN<16>
  VSS(49)  = GND
  DQ(62)  = M_E_DQ<63>
  VSS(48)  = GND
  DQ(58)  = M_E_DQ<59>
  VSS(47)  = GND
  SA(0)  = GND
  SA(1)  = PVPP_DEF
  SCL  = SMB_DDR_DEF_VPP_SCL
  VPP(4)  = PVPP_DEF
  VPP(3)  = PVPP_DEF
  RFU(2)  = TP_CH_E_DIMM_E0_RFU_2
  \12v\(0)  = P12V_NVDIMM_DEF
  VREFCA  = M_E_VREF
  VSS(46)  = GND
  DQ(5)  = M_E_DQ<4>
  VSS(45)  = GND
  DQ(1)  = M_E_DQ<0>
  VSS(44)  = GND
  DQS0N  = M_E_DQS_DN<0>
  DQS0P  = M_E_DQS_DP<0>
  VSS(43)  = GND
  DQ(7)  = M_E_DQ<6>
  VSS(42)  = GND
  DQ(3)  = M_E_DQ<2>
  VSS(41)  = GND
  DQ(13)  = M_E_DQ<12>
  VSS(40)  = GND
  DQ(9)  = M_E_DQ<8>
  VSS(39)  = GND
  DQS1N  = M_E_DQS_DN<1>
  DQS1P  = M_E_DQS_DP<1>
  VSS(38)  = GND
  DQ(15)  = M_E_DQ<14>
  VSS(37)  = GND
  DQ(11)  = M_E_DQ<10>
  VSS(36)  = GND
  DQ(21)  = M_E_DQ<20>
  VSS(35)  = GND
  DQ(17)  = M_E_DQ<16>
  VSS(34)  = GND
  DQS2N  = M_E_DQS_DN<2>
  DQS2P  = M_E_DQS_DP<2>
  VSS(33)  = GND
  DQ(23)  = M_E_DQ<22>
  VSS(32)  = GND
  DQ(19)  = M_E_DQ<18>
  VSS(31)  = GND
  DQ(29)  = M_E_DQ<28>
  VSS(30)  = GND
  DQ(25)  = M_E_DQ<24>
  VSS(29)  = GND
  DQS3N  = M_E_DQS_DN<3>
  DQS3P  = M_E_DQS_DP<3>
  VSS(28)  = GND
  DQ(31)  = M_E_DQ<30>
  VSS(27)  = GND
  DQ(27)  = M_E_DQ<26>
  VSS(26)  = GND
  CB(5)  = M_E_ECC<4>
  VSS(25)  = GND
  CB(1)  = M_E_ECC<0>
  VSS(24)  = GND
  DQS8N  = M_E_DQS_DN<8>
  DQS8P  = M_E_DQS_DP<8>
  VSS(23)  = GND
  CB(7)  = M_E_ECC<6>
  VSS(22)  = GND
  CB(3)  = M_E_ECC<2>
  VSS(21)  = GND
  CKE(1)  = M_E_CKE<1>
  VDD(12)  = PVDDQ_DEF
  RFU(0)  = TP_CH_E_DIMM_E0_RFU_0
  VDD(11)  = PVDDQ_DEF
  BG(1)  = M_E_BG<1>
  ALERT_N  = M_E_ALERT_N
  VDD(10)  = PVDDQ_DEF
  A11  = M_E_MA<11>
  A7  = M_E_MA<7>
  VDD(9)  = PVDDQ_DEF
  A5  = M_E_MA<5>
  A4  = M_E_MA<4>
  VDD(8)  = PVDDQ_DEF
  A2  = M_E_MA<2>
  VDD(7)  = PVDDQ_DEF
  CK1P  = M_E_CLK_DP<1>
  CK1N  = M_E_CLK_DN<1>
  VDD(6)  = PVDDQ_DEF
  VTT(0)  = PVTT_DEF
  PAR  = M_E_PAR
  VDD(5)  = PVDDQ_DEF
  BA(1)  = M_E_BA<1>
  A10  = M_E_MA<10>
  VDD(4)  = PVDDQ_DEF
  RFU(1)  = TP_CH_E_DIMM_E0_RFU_1
  A14_WE_N  = M_E_MA<14>
  VDD(3)  = PVDDQ_DEF
  SAVE_N_NC  = FM_ADR_COMPLETE_DEF_N
  VDD(2)  = PVDDQ_DEF
  A13  = M_E_MA<13>
  VDD(1)  = PVDDQ_DEF
  A17  = M_E_MA<17>
  C(2)  = M_E_C<2>
  VDD(0)  = PVDDQ_DEF
  S3_N_C(1)  = M_E_CS_N<3>
  SA(2)  = GND
  VSS(20)  = GND
  DQ(37)  = M_E_DQ<36>
  VSS(19)  = GND
  DQ(33)  = M_E_DQ<32>
  VSS(18)  = GND
  DQS4N  = M_E_DQS_DN<4>
  DQS4P  = M_E_DQS_DP<4>
  VSS(17)  = GND
  DQ(39)  = M_E_DQ<38>
  VSS(16)  = GND
  DQ(35)  = M_E_DQ<34>
  VSS(15)  = GND
  DQ(45)  = M_E_DQ<44>
  VSS(14)  = GND
  DQ(41)  = M_E_DQ<40>
  VSS(13)  = GND
  DQS5N  = M_E_DQS_DN<5>
  DQS5P  = M_E_DQS_DP<5>
  VSS(12)  = GND
  DQ(47)  = M_E_DQ<46>
  VSS(11)  = GND
  DQ(43)  = M_E_DQ<42>
  VSS(10)  = GND
  DQ(53)  = M_E_DQ<52>
  VSS(9)  = GND
  DQ(49)  = M_E_DQ<48>
  VSS(8)  = GND
  DQS6N  = M_E_DQS_DN<6>
  DQS6P  = M_E_DQS_DP<6>
  VSS(7)  = GND
  DQ(55)  = M_E_DQ<54>
  VSS(6)  = GND
  DQ(51)  = M_E_DQ<50>
  VSS(5)  = GND
  DQ(61)  = M_E_DQ<60>
  VSS(4)  = GND
  DQ(57)  = M_E_DQ<56>
  VSS(3)  = GND
  DQS7N  = M_E_DQS_DN<7>
  DQS7P  = M_E_DQS_DP<7>
  VSS(2)  = GND
  DQ(63)  = M_E_DQ<62>
  VSS(1)  = GND
  DQ(59)  = M_E_DQ<58>
  VSS(0)  = GND
  VDDSPD  = PVPP_DEF
  SDA  = SMB_DDR_DEF_VPP_SDA
  VPP(1)  = PVPP_DEF
  VPP(0)  = PVPP_DEF
  VPP(2)  = PVPP_DEF

(kicad_pcb
	(version 20260206)
	(generator "pcbnew")
	(generator_version "10.0")
	(general
		(thickness 1.6)
		(legacy_teardrops no)
	)
	(paper "A4")
	(title_block
		(title "Wiwynn_Tioga_Pass_MB.brd")
		(comment 1 "Tioga Pass / footprint 2096 of 4770 (J4A2), pads 252-291 of 291")
	)
	(layers
		(0 "F.Cu" signal "TOP")
		(4 "In1.Cu" signal "L2GND")
		(6 "In2.Cu" signal "L3")
		(8 "In3.Cu" signal "L4GND")
		(10 "In4.Cu" signal "L5")
		(12 "In5.Cu" signal "L6GND")
		(14 "In6.Cu" signal "L7VCC")
		(16 "In7.Cu" signal "L8VCC")
		(18 "In8.Cu" signal "L9GND")
		(20 "In9.Cu" signal "L10")
		(22 "In10.Cu" signal "L11GND")
		(24 "In11.Cu" signal "L12")
		(26 "In12.Cu" signal "L13GND")
		(2 "B.Cu" signal "BOTTOM")
		(9 "F.Adhes" user "F.Adhesive")
		(11 "B.Adhes" user "B.Adhesive")
		(13 "F.Paste" user "Package Geometry/Pastemask Top")
		(15 "B.Paste" user "Package Geometry/Pastemask Bottom")
		(5 "F.SilkS" user "Ref Des/Silkscreen Top")
		(7 "B.SilkS" user "Ref Des/Silkscreen Bottom")
		(1 "F.Mask" user "Board Geometry/Soldermask Top")
		(3 "B.Mask" user "Board Geometry/Soldermask Bottom")
		(17 "Dwgs.User" user "User.Drawings")
		(19 "Cmts.User" user "User.Comments")
		(21 "Eco1.User" user "User.Eco1")
		(23 "Eco2.User" user "User.Eco2")
		(25 "Edge.Cuts" user "Board Geometry/Outline")
		(27 "Margin" user)
		(31 "F.CrtYd" user "Package Geometry/Place Bound Top")
		(29 "B.CrtYd" user "Package Geometry/Place Bound Bottom")
		(35 "F.Fab" user "Ref Des/Assembly Top")
		(33 "B.Fab" user "Ref Des/Assembly Bottom")
	)
	(footprint ""
		(layer "F.Cu")
		(at 194.700398 -142.6718 90)
		(property "Reference" "J4A2"
			(at -2.369312 42.66311 0)
			(unlocked yes)
			(layer "F.SilkS")
			(effects
				(font
					(size 0.7874 0.5842)
					(thickness 0.1524)
				)
				(justify left)
			)
		)
		(property "Value" ""
			(at 0 0 90)
			(layer "F.Fab")
			(effects
				(font
					(size 1.27 1.27)
				)
			)
		)
		(duplicate_pad_numbers_are_jumpers no)
		(pad "249" smd rect
			(at 4.59994 93.49994 90)
			(size 1.8034 0.508)
			(layers "F.Cu" "F.Mask" "F.Paste")
			(net "M_E_DQ<34>")
		)
		(pad "250" smd rect
			(at 4.59994 94.350078 90)
			(size 1.8034 0.508)
			(layers "F.Cu" "F.Mask" "F.Paste")
			(net "GND")
		)
		(pad "251" smd rect
			(at 4.59994 95.199962 90)
			(size 1.8034 0.508)
			(layers "F.Cu" "F.Mask" "F.Paste")
			(net "M_E_DQ<44>")
		)
		(pad "252" smd rect
			(at 4.59994 96.0501 90)
			(size 1.8034 0.508)
			(layers "F.Cu" "F.Mask" "F.Paste")
			(net "GND")
		)
		(pad "253" smd rect
			(at 4.59994 96.899984 90)
			(size 1.8034 0.508)
			(layers "F.Cu" "F.Mask" "F.Paste")
			(net "M_E_DQ<40>")
		)
		(pad "254" smd rect
			(at 4.59994 97.750122 90)
			(size 1.8034 0.508)
			(layers "F.Cu" "F.Mask" "F.Paste")
			(net "GND")
		)
		(pad "255" smd rect
			(at 4.59994 98.600006 90)
			(size 1.8034 0.508)
			(layers "F.Cu" "F.Mask" "F.Paste")
			(net "M_E_DQS_DN<5>")
		)
		(pad "256" smd rect
			(at 4.59994 99.44989 90)
			(size 1.8034 0.508)
			(layers "F.Cu" "F.Mask" "F.Paste")
			(net "M_E_DQS_DP<5>")
		)
		(pad "257" smd rect
			(at 4.59994 100.300028 90)
			(size 1.8034 0.508)
			(layers "F.Cu" "F.Mask" "F.Paste")
			(net "GND")
		)
		(pad "258" smd rect
			(at 4.59994 101.149912 90)
			(size 1.8034 0.508)
			(layers "F.Cu" "F.Mask" "F.Paste")
			(net "M_E_DQ<46>")
		)
		(pad "259" smd rect
			(at 4.59994 102.00005 90)
			(size 1.8034 0.508)
			(layers "F.Cu" "F.Mask" "F.Paste")
			(net "GND")
		)
		(pad "260" smd rect
			(at 4.59994 102.849934 90)
			(size 1.8034 0.508)
			(layers "F.Cu" "F.Mask" "F.Paste")
			(net "M_E_DQ<42>")
		)
		(pad "261" smd rect
			(at 4.59994 103.700072 90)
			(size 1.8034 0.508)
			(layers "F.Cu" "F.Mask" "F.Paste")
			(net "GND")
		)
		(pad "262" smd rect
			(at 4.59994 104.549956 90)
			(size 1.8034 0.508)
			(layers "F.Cu" "F.Mask" "F.Paste")
			(net "M_E_DQ<52>")
		)
		(pad "263" smd rect
			(at 4.59994 105.400094 90)
			(size 1.8034 0.508)
			(layers "F.Cu" "F.Mask" "F.Paste")
			(net "GND")
		)
		(pad "264" smd rect
			(at 4.59994 106.249978 90)
			(size 1.8034 0.508)
			(layers "F.Cu" "F.Mask" "F.Paste")
			(net "M_E_DQ<48>")
		)
		(pad "265" smd rect
			(at 4.59994 107.100116 90)
			(size 1.8034 0.508)
			(layers "F.Cu" "F.Mask" "F.Paste")
			(net "GND")
		)
		(pad "266" smd rect
			(at 4.59994 107.95 90)
			(size 1.8034 0.508)
			(layers "F.Cu" "F.Mask" "F.Paste")
			(net "M_E_DQS_DN<6>")
		)
		(pad "267" smd rect
			(at 4.59994 108.799884 90)
			(size 1.8034 0.508)
			(layers "F.Cu" "F.Mask" "F.Paste")
			(net "M_E_DQS_DP<6>")
		)
		(pad "268" smd rect
			(at 4.59994 109.650022 90)
			(size 1.8034 0.508)
			(layers "F.Cu" "F.Mask" "F.Paste")
			(net "GND")
		)
		(pad "269" smd rect
			(at 4.59994 110.499906 90)
			(size 1.8034 0.508)
			(layers "F.Cu" "F.Mask" "F.Paste")
			(net "M_E_DQ<54>")
		)
		(pad "270" smd rect
			(at 4.59994 111.350044 90)
			(size 1.8034 0.508)
			(layers "F.Cu" "F.Mask" "F.Paste")
			(net "GND")
		)
		(pad "271" smd rect
			(at 4.59994 112.199928 90)
			(size 1.8034 0.508)
			(layers "F.Cu" "F.Mask" "F.Paste")
			(net "M_E_DQ<50>")
		)
		(pad "272" smd rect
			(at 4.59994 113.050066 90)
			(size 1.8034 0.508)
			(layers "F.Cu" "F.Mask" "F.Paste")
			(net "GND")
		)
		(pad "273" smd rect
			(at 4.59994 113.89995 90)
			(size 1.8034 0.508)
			(layers "F.Cu" "F.Mask" "F.Paste")
			(net "M_E_DQ<60>")
		)
		(pad "274" smd rect
			(at 4.59994 114.750088 90)
			(size 1.8034 0.508)
			(layers "F.Cu" "F.Mask" "F.Paste")
			(net "GND")
		)
		(pad "275" smd rect
			(at 4.59994 115.599972 90)
			(size 1.8034 0.508)
			(layers "F.Cu" "F.Mask" "F.Paste")
			(net "M_E_DQ<56>")
		)
		(pad "276" smd rect
			(at 4.59994 116.45011 90)
			(size 1.8034 0.508)
			(layers "F.Cu" "F.Mask" "F.Paste")
			(net "GND")
		)
		(pad "277" smd rect
			(at 4.59994 117.299994 90)
			(size 1.8034 0.508)
			(layers "F.Cu" "F.Mask" "F.Paste")
			(net "M_E_DQS_DN<7>")
		)
		(pad "278" smd rect
			(at 4.59994 118.149878 90)
			(size 1.8034 0.508)
			(layers "F.Cu" "F.Mask" "F.Paste")
			(net "M_E_DQS_DP<7>")
		)
		(pad "279" smd rect
			(at 4.59994 119.000016 90)
			(size 1.8034 0.508)
			(layers "F.Cu" "F.Mask" "F.Paste")
			(net "GND")
		)
		(pad "280" smd rect
			(at 4.59994 119.8499 90)
			(size 1.8034 0.508)
			(layers "F.Cu" "F.Mask" "F.Paste")
			(net "M_E_DQ<62>")
		)
		(pad "281" smd rect
			(at 4.59994 120.700038 90)
			(size 1.8034 0.508)
			(layers "F.Cu" "F.Mask" "F.Paste")
			(net "GND")
		)
		(pad "282" smd rect
			(at 4.59994 121.549922 90)
			(size 1.8034 0.508)
			(layers "F.Cu" "F.Mask" "F.Paste")
			(net "M_E_DQ<58>")
		)
		(pad "283" smd rect
			(at 4.59994 122.40006 90)
			(size 1.8034 0.508)
			(layers "F.Cu" "F.Mask" "F.Paste")
			(net "GND")
		)
		(pad "284" smd rect
			(at 4.59994 123.249944 90)
			(size 1.8034 0.508)
			(layers "F.Cu" "F.Mask" "F.Paste")
			(net "PVPP_DEF")
		)
		(pad "285" smd rect
			(at 4.59994 124.100082 90)
			(size 1.8034 0.508)
			(layers "F.Cu" "F.Mask" "F.Paste")
			(net "SMB_DDR_DEF_VPP_SDA")
		)
		(pad "286" smd rect
			(at 4.59994 124.949966 90)
			(size 1.8034 0.508)
			(layers "F.Cu" "F.Mask" "F.Paste")
			(net "PVPP_DEF")
		)
		(pad "287" smd rect
			(at 4.59994 125.800104 90)
			(size 1.8034 0.508)
			(layers "F.Cu" "F.Mask" "F.Paste")
			(net "PVPP_DEF")
		)
		(pad "288" smd rect
			(at 4.59994 126.649988 90)
			(size 1.8034 0.508)
			(layers "F.Cu" "F.Mask" "F.Paste")
			(net "PVPP_DEF")
		)
	)
)
